FILE_TYPE = MACRO_DRAWING;
SET COLOR_WIRE YELLOW;
SET COLOR_PROP ORANGE;
SET COLOR_DOT WHITE;
SET COLOR_ARC YELLOW;
SET COLOR_BODY GREEN;
SET COLOR_NOTE PURPLE;
SET PROP_DISPLAY VALUE;
SET PAGE_NUMBER P427;
FORCEADD PT5161LRS..6
(-7675 4375);
FORCEPROP 1 LAST LOCATION U6013
J 0
(-8025 6000);
DISPLAY 0.723404 (-8025 6000);
PAINT GREEN (-8025 6000);
FORCEPROP 0 LAST $SEC 6
J 0
(-8025 6150);
DISPLAY 0.680851 (-8025 6150);
PAINT MONO (-8025 6150);
DISPLAY INVISIBLE (-8025 6150);
FORCEPROP 0 LAST CDS_SEC 6
J 0
(-8025 6150);
DISPLAY 0.680851 (-8025 6150);
DISPLAY INVISIBLE (-8025 6150);
FORCEPROP 0 LASTPIN (-7225 5525) $PN P29
J 0
(-7215 5535);
DISPLAY 0.680851 (-7215 5535);
PAINT MONO (-7215 5535);
FORCEPROP 0 LASTPIN (-7225 5175) $PN AA29
J 0
(-7215 5185);
DISPLAY 0.680851 (-7215 5185);
PAINT MONO (-7215 5185);
FORCEPROP 0 LASTPIN (-7225 4825) $PN AH29
J 0
(-7215 4835);
DISPLAY 0.680851 (-7215 4835);
PAINT MONO (-7215 4835);
FORCEPROP 0 LASTPIN (-7225 4475) $PN AR29
J 0
(-7215 4485);
DISPLAY 0.680851 (-7215 4485);
PAINT MONO (-7215 4485);
FORCEPROP 0 LASTPIN (-7225 4125) $PN BB29
J 0
(-7215 4135);
DISPLAY 0.680851 (-7215 4135);
PAINT MONO (-7215 4135);
FORCEPROP 0 LASTPIN (-7225 3775) $PN BJ29
J 0
(-7215 3785);
DISPLAY 0.680851 (-7215 3785);
PAINT MONO (-7215 3785);
FORCEPROP 0 LASTPIN (-7225 3425) $PN BT29
J 0
(-7215 3435);
DISPLAY 0.680851 (-7215 3435);
PAINT MONO (-7215 3435);
FORCEPROP 0 LASTPIN (-7225 3075) $PN CC29
J 0
(-7215 3085);
DISPLAY 0.680851 (-7215 3085);
PAINT MONO (-7215 3085);
FORCEPROP 0 LASTPIN (-7225 5625) $PN M26
J 0
(-7215 5635);
DISPLAY 0.680851 (-7215 5635);
PAINT MONO (-7215 5635);
FORCEPROP 0 LASTPIN (-7225 5275) $PN W26
J 0
(-7215 5285);
DISPLAY 0.680851 (-7215 5285);
PAINT MONO (-7215 5285);
FORCEPROP 0 LASTPIN (-7225 4925) $PN AF26
J 0
(-7215 4935);
DISPLAY 0.680851 (-7215 4935);
PAINT MONO (-7215 4935);
FORCEPROP 0 LASTPIN (-7225 4575) $PN AN26
J 0
(-7215 4585);
DISPLAY 0.680851 (-7215 4585);
PAINT MONO (-7215 4585);
FORCEPROP 0 LASTPIN (-7225 4225) $PN AY26
J 0
(-7215 4235);
DISPLAY 0.680851 (-7215 4235);
PAINT MONO (-7215 4235);
FORCEPROP 0 LASTPIN (-7225 3875) $PN BG26
J 0
(-7215 3885);
DISPLAY 0.680851 (-7215 3885);
PAINT MONO (-7215 3885);
FORCEPROP 0 LASTPIN (-7225 3525) $PN BP26
J 0
(-7215 3535);
DISPLAY 0.680851 (-7215 3535);
PAINT MONO (-7215 3535);
FORCEPROP 0 LASTPIN (-7225 3175) $PN CA26
J 0
(-7215 3185);
DISPLAY 0.680851 (-7215 3185);
PAINT MONO (-7215 3185);
FORCEPROP 2 LAST PART_TYPE SMLF
J 0
(-8025 6100);
DISPLAY 0.680851 (-8025 6100);
FORCEPROP 1 LAST MATERIAL IC
J 0
(-8025 5850);
DISPLAY 0.723404 (-8025 5850);
PAINT GREEN (-8025 5850);
FORCEPROP 2 LAST VALUE PT5161LRS
J 0
(-8025 6050);
DISPLAY 0.680851 (-8025 6050);
FORCEPROP 1 LAST NEEDS_NO_SIZE TRUE
J 0
(-7675 4375);
DISPLAY 0.723404 (-7675 4375);
PAINT GREEN (-7675 4375);
DISPLAY INVISIBLE (-7675 4375);
FORCEPROP 1 LAST CDS_LMAN_SYM_OUTLINE -350,1450,300,-1400
J 0
(-7675 4375);
DISPLAY 0.468085 (-7675 4375);
PAINT GREEN (-7675 4375);
DISPLAY INVISIBLE (-7675 4375);
FORCEPROP 2 LAST CDS_LIB pure_quanta
J 0
(-7675 4375);
DISPLAY INVISIBLE (-7675 4375);
FORCEPROP 1 LAST PATH I1
J 0
(-7675 4375);
DISPLAY 0.723404 (-7675 4375);
PAINT GREEN (-7675 4375);
DISPLAY INVISIBLE (-7675 4375);
FORCEPROP 1 LAST PART_NUMBER AJ051610U03
J 0
(-8025 5925);
DISPLAY 0.723404 (-8025 5925);
PAINT GREEN (-8025 5925);
DISPLAY INVISIBLE (-8025 5925);
FORCEADD TAP..1
(-6450 4125);
FORCEPROP 3 LASTPIN (-6500 4125) SIG_NAME P5E_CPU0_P3_RX_DN<11>
J 0
(-6490 4135);
DISPLAY 0.659574 (-6490 4135);
PAINT MONO (-6490 4135);
DISPLAY INVISIBLE (-6490 4135);
FORCEPROP 1 LASTPIN (-6500 4125) BN 11
J 0
(-6512 4133);
DISPLAY 0.680851 (-6512 4133);
PAINT GREEN (-6512 4133);
FORCEPROP 2 LAST CDS_LIB standard
J 0
(-6450 4125);
DISPLAY INVISIBLE (-6450 4125);
FORCEPROP 1 LAST BODY_TYPE PLUMBING
J 0
(-6450 4175);
DISPLAY 0.872340 (-6450 4175);
PAINT GREEN (-6450 4175);
DISPLAY INVISIBLE (-6450 4175);
FORCEPROP 1 LAST HDL_TAP TRUE
J 0
(-6125 4000);
DISPLAY 0.872340 (-6125 4000);
DISPLAY INVISIBLE (-6125 4000);
FORCEPROP 1 LAST PATH I10
J 0
(-6452 4125);
DISPLAY 0.872340 (-6452 4125);
PAINT GREEN (-6452 4125);
DISPLAY INVISIBLE (-6452 4125);
FORCEADD TAP..1
(-6450 4475);
FORCEPROP 3 LASTPIN (-6500 4475) SIG_NAME P5E_CPU0_P3_RX_DN<12>
J 0
(-6490 4485);
DISPLAY 0.659574 (-6490 4485);
PAINT MONO (-6490 4485);
DISPLAY INVISIBLE (-6490 4485);
FORCEPROP 1 LASTPIN (-6500 4475) BN 12
J 0
(-6512 4483);
DISPLAY 0.680851 (-6512 4483);
PAINT GREEN (-6512 4483);
FORCEPROP 2 LAST CDS_LIB standard
J 0
(-6450 4475);
DISPLAY INVISIBLE (-6450 4475);
FORCEPROP 1 LAST BODY_TYPE PLUMBING
J 0
(-6450 4525);
DISPLAY 0.872340 (-6450 4525);
PAINT GREEN (-6450 4525);
DISPLAY INVISIBLE (-6450 4525);
FORCEPROP 1 LAST HDL_TAP TRUE
J 0
(-6125 4350);
DISPLAY 0.872340 (-6125 4350);
DISPLAY INVISIBLE (-6125 4350);
FORCEPROP 1 LAST PATH I11
J 0
(-6452 4475);
DISPLAY 0.872340 (-6452 4475);
PAINT GREEN (-6452 4475);
DISPLAY INVISIBLE (-6452 4475);
FORCEADD TAP..1
(-6650 4925);
FORCEPROP 3 LASTPIN (-6700 4925) SIG_NAME P5E_CPU0_P3_RX_DP<13>
J 0
(-6690 4935);
DISPLAY 0.659574 (-6690 4935);
PAINT MONO (-6690 4935);
DISPLAY INVISIBLE (-6690 4935);
FORCEPROP 1 LASTPIN (-6700 4925) BN 13
J 0
(-6712 4933);
DISPLAY 0.680851 (-6712 4933);
PAINT GREEN (-6712 4933);
FORCEPROP 2 LAST CDS_LIB standard
J 0
(-6650 4925);
DISPLAY INVISIBLE (-6650 4925);
FORCEPROP 1 LAST BODY_TYPE PLUMBING
J 0
(-6650 4975);
DISPLAY 0.872340 (-6650 4975);
PAINT GREEN (-6650 4975);
DISPLAY INVISIBLE (-6650 4975);
FORCEPROP 1 LAST HDL_TAP TRUE
J 0
(-6325 4800);
DISPLAY 0.872340 (-6325 4800);
DISPLAY INVISIBLE (-6325 4800);
FORCEPROP 1 LAST PATH I12
J 0
(-6652 4925);
DISPLAY 0.872340 (-6652 4925);
PAINT GREEN (-6652 4925);
DISPLAY INVISIBLE (-6652 4925);
FORCEADD TAP..1
(-6650 5275);
FORCEPROP 3 LASTPIN (-6700 5275) SIG_NAME P5E_CPU0_P3_RX_DP<14>
J 0
(-6690 5285);
DISPLAY 0.659574 (-6690 5285);
PAINT MONO (-6690 5285);
DISPLAY INVISIBLE (-6690 5285);
FORCEPROP 1 LASTPIN (-6700 5275) BN 14
J 0
(-6712 5283);
DISPLAY 0.680851 (-6712 5283);
PAINT GREEN (-6712 5283);
FORCEPROP 2 LAST CDS_LIB standard
J 0
(-6650 5275);
DISPLAY INVISIBLE (-6650 5275);
FORCEPROP 1 LAST BODY_TYPE PLUMBING
J 0
(-6650 5325);
DISPLAY 0.872340 (-6650 5325);
PAINT GREEN (-6650 5325);
DISPLAY INVISIBLE (-6650 5325);
FORCEPROP 1 LAST HDL_TAP TRUE
J 0
(-6325 5150);
DISPLAY 0.872340 (-6325 5150);
DISPLAY INVISIBLE (-6325 5150);
FORCEPROP 1 LAST PATH I13
J 0
(-6652 5275);
DISPLAY 0.872340 (-6652 5275);
PAINT GREEN (-6652 5275);
DISPLAY INVISIBLE (-6652 5275);
FORCEADD TAP..1
(-6450 4825);
FORCEPROP 3 LASTPIN (-6500 4825) SIG_NAME P5E_CPU0_P3_RX_DN<13>
J 0
(-6490 4835);
DISPLAY 0.659574 (-6490 4835);
PAINT MONO (-6490 4835);
DISPLAY INVISIBLE (-6490 4835);
FORCEPROP 1 LASTPIN (-6500 4825) BN 13
J 0
(-6512 4833);
DISPLAY 0.680851 (-6512 4833);
PAINT GREEN (-6512 4833);
FORCEPROP 2 LAST CDS_LIB standard
J 0
(-6450 4825);
DISPLAY INVISIBLE (-6450 4825);
FORCEPROP 1 LAST BODY_TYPE PLUMBING
J 0
(-6450 4875);
DISPLAY 0.872340 (-6450 4875);
PAINT GREEN (-6450 4875);
DISPLAY INVISIBLE (-6450 4875);
FORCEPROP 1 LAST HDL_TAP TRUE
J 0
(-6125 4700);
DISPLAY 0.872340 (-6125 4700);
DISPLAY INVISIBLE (-6125 4700);
FORCEPROP 1 LAST PATH I14
J 0
(-6452 4825);
DISPLAY 0.872340 (-6452 4825);
PAINT GREEN (-6452 4825);
DISPLAY INVISIBLE (-6452 4825);
FORCEADD TAP..1
(-6450 5175);
FORCEPROP 3 LASTPIN (-6500 5175) SIG_NAME P5E_CPU0_P3_RX_DN<14>
J 0
(-6490 5185);
DISPLAY 0.659574 (-6490 5185);
PAINT MONO (-6490 5185);
DISPLAY INVISIBLE (-6490 5185);
FORCEPROP 1 LASTPIN (-6500 5175) BN 14
J 0
(-6512 5183);
DISPLAY 0.680851 (-6512 5183);
PAINT GREEN (-6512 5183);
FORCEPROP 2 LAST CDS_LIB standard
J 0
(-6450 5175);
DISPLAY INVISIBLE (-6450 5175);
FORCEPROP 1 LAST BODY_TYPE PLUMBING
J 0
(-6450 5225);
DISPLAY 0.872340 (-6450 5225);
PAINT GREEN (-6450 5225);
DISPLAY INVISIBLE (-6450 5225);
FORCEPROP 1 LAST HDL_TAP TRUE
J 0
(-6125 5050);
DISPLAY 0.872340 (-6125 5050);
DISPLAY INVISIBLE (-6125 5050);
FORCEPROP 1 LAST PATH I15
J 0
(-6452 5175);
DISPLAY 0.872340 (-6452 5175);
PAINT GREEN (-6452 5175);
DISPLAY INVISIBLE (-6452 5175);
FORCEADD TAP..1
(-6450 5525);
FORCEPROP 3 LASTPIN (-6500 5525) SIG_NAME P5E_CPU0_P3_RX_DN<15>
J 0
(-6490 5535);
DISPLAY 0.659574 (-6490 5535);
PAINT MONO (-6490 5535);
DISPLAY INVISIBLE (-6490 5535);
FORCEPROP 1 LASTPIN (-6500 5525) BN 15
J 0
(-6512 5533);
DISPLAY 0.680851 (-6512 5533);
PAINT GREEN (-6512 5533);
FORCEPROP 2 LAST CDS_LIB standard
J 0
(-6450 5525);
DISPLAY INVISIBLE (-6450 5525);
FORCEPROP 1 LAST BODY_TYPE PLUMBING
J 0
(-6450 5575);
DISPLAY 0.872340 (-6450 5575);
PAINT GREEN (-6450 5575);
DISPLAY INVISIBLE (-6450 5575);
FORCEPROP 1 LAST HDL_TAP TRUE
J 0
(-6125 5400);
DISPLAY 0.872340 (-6125 5400);
DISPLAY INVISIBLE (-6125 5400);
FORCEPROP 1 LAST PATH I16
J 0
(-6452 5525);
DISPLAY 0.872340 (-6452 5525);
PAINT GREEN (-6452 5525);
DISPLAY INVISIBLE (-6452 5525);
FORCEADD TAP..1
(-6650 5625);
FORCEPROP 3 LASTPIN (-6700 5625) SIG_NAME P5E_CPU0_P3_RX_DP<15>
J 0
(-6690 5635);
DISPLAY 0.659574 (-6690 5635);
PAINT MONO (-6690 5635);
DISPLAY INVISIBLE (-6690 5635);
FORCEPROP 1 LASTPIN (-6700 5625) BN 15
J 0
(-6712 5633);
DISPLAY 0.680851 (-6712 5633);
PAINT GREEN (-6712 5633);
FORCEPROP 2 LAST CDS_LIB standard
J 0
(-6650 5625);
DISPLAY INVISIBLE (-6650 5625);
FORCEPROP 1 LAST BODY_TYPE PLUMBING
J 0
(-6650 5675);
DISPLAY 0.872340 (-6650 5675);
PAINT GREEN (-6650 5675);
DISPLAY INVISIBLE (-6650 5675);
FORCEPROP 1 LAST HDL_TAP TRUE
J 0
(-6325 5500);
DISPLAY 0.872340 (-6325 5500);
DISPLAY INVISIBLE (-6325 5500);
FORCEPROP 1 LAST PATH I17
J 0
(-6652 5625);
DISPLAY 0.872340 (-6652 5625);
PAINT GREEN (-6652 5625);
DISPLAY INVISIBLE (-6652 5625);
FORCEADD OFFPAGE..5
R 2
(-5450 5600);
FORCEPROP 2 LAST $XR0 25 
J 0
(-5261 5600);
DISPLAY 0.638298 (-5261 5600);
PAINT MONO (-5261 5600);
FORCEPROP 2 LAST CDS_LIB standard
J 0
(-5450 5600);
DISPLAY INVISIBLE (-5450 5600);
FORCEPROP 1 LAST OFFPAGE TRUE
J 2
(-5775 5475);
DISPLAY 0.872340 (-5775 5475);
PAINT GREEN (-5775 5475);
DISPLAY INVISIBLE (-5775 5475);
FORCEPROP 1 LAST COMMENT_BODY TRUE
J 2
(-5550 5525);
DISPLAY 0.872340 (-5550 5525);
PAINT GREEN (-5550 5525);
DISPLAY INVISIBLE (-5550 5525);
FORCEPROP 2 LAST PATH I18
J 0
(-5275 5675);
DISPLAY 0.680851 (-5275 5675);
DISPLAY INVISIBLE (-5275 5675);
FORCEADD OFFPAGE..5
R 2
(-5425 5725);
FORCEPROP 2 LAST $XR0 25 
J 0
(-5236 5725);
DISPLAY 0.638298 (-5236 5725);
PAINT MONO (-5236 5725);
FORCEPROP 2 LAST CDS_LIB standard
J 0
(-5425 5725);
DISPLAY INVISIBLE (-5425 5725);
FORCEPROP 1 LAST OFFPAGE TRUE
J 2
(-5750 5600);
DISPLAY 0.872340 (-5750 5600);
PAINT GREEN (-5750 5600);
DISPLAY INVISIBLE (-5750 5600);
FORCEPROP 1 LAST COMMENT_BODY TRUE
J 2
(-5525 5650);
DISPLAY 0.872340 (-5525 5650);
PAINT GREEN (-5525 5650);
DISPLAY INVISIBLE (-5525 5650);
FORCEPROP 2 LAST PATH I19
J 0
(-5250 5800);
DISPLAY 0.680851 (-5250 5800);
DISPLAY INVISIBLE (-5250 5800);
FORCEADD TAP..1
(-6650 3175);
FORCEPROP 3 LASTPIN (-6700 3175) SIG_NAME P5E_CPU0_P3_RX_DP<8>
J 0
(-6690 3185);
DISPLAY 0.659574 (-6690 3185);
PAINT MONO (-6690 3185);
DISPLAY INVISIBLE (-6690 3185);
FORCEPROP 1 LASTPIN (-6700 3175) BN 8
J 0
(-6712 3183);
DISPLAY 0.680851 (-6712 3183);
PAINT GREEN (-6712 3183);
FORCEPROP 2 LAST CDS_LIB standard
J 0
(-6650 3175);
DISPLAY INVISIBLE (-6650 3175);
FORCEPROP 1 LAST BODY_TYPE PLUMBING
J 0
(-6650 3225);
DISPLAY 0.872340 (-6650 3225);
PAINT GREEN (-6650 3225);
DISPLAY INVISIBLE (-6650 3225);
FORCEPROP 1 LAST HDL_TAP TRUE
J 0
(-6325 3050);
DISPLAY 0.872340 (-6325 3050);
DISPLAY INVISIBLE (-6325 3050);
FORCEPROP 1 LAST PATH I2
J 0
(-6652 3175);
DISPLAY 0.872340 (-6652 3175);
PAINT GREEN (-6652 3175);
DISPLAY INVISIBLE (-6652 3175);
FORCEADD TAP..1
(-2150 3125);
FORCEPROP 3 LASTPIN (-2200 3125) SIG_NAME P5E_CPU0_P3_RX_DP<0>
J 0
(-2190 3135);
DISPLAY 0.659574 (-2190 3135);
PAINT MONO (-2190 3135);
DISPLAY INVISIBLE (-2190 3135);
FORCEPROP 1 LASTPIN (-2200 3125) BN 0
J 0
(-2212 3133);
DISPLAY 0.680851 (-2212 3133);
PAINT GREEN (-2212 3133);
FORCEPROP 2 LAST CDS_LIB standard
J 0
(-2150 3125);
DISPLAY INVISIBLE (-2150 3125);
FORCEPROP 1 LAST BODY_TYPE PLUMBING
J 0
(-2150 3175);
DISPLAY 0.872340 (-2150 3175);
PAINT GREEN (-2150 3175);
DISPLAY INVISIBLE (-2150 3175);
FORCEPROP 1 LAST HDL_TAP TRUE
J 0
(-1825 3000);
DISPLAY 0.872340 (-1825 3000);
DISPLAY INVISIBLE (-1825 3000);
FORCEPROP 1 LAST PATH I20
J 0
(-2152 3125);
DISPLAY 0.872340 (-2152 3125);
PAINT GREEN (-2152 3125);
DISPLAY INVISIBLE (-2152 3125);
FORCEADD TAP..1
(-1950 3025);
FORCEPROP 3 LASTPIN (-2000 3025) SIG_NAME P5E_CPU0_P3_RX_DN<0>
J 0
(-1990 3035);
DISPLAY 0.659574 (-1990 3035);
PAINT MONO (-1990 3035);
DISPLAY INVISIBLE (-1990 3035);
FORCEPROP 1 LASTPIN (-2000 3025) BN 0
J 0
(-2012 3033);
DISPLAY 0.680851 (-2012 3033);
PAINT GREEN (-2012 3033);
FORCEPROP 2 LAST CDS_LIB standard
J 0
(-1950 3025);
DISPLAY INVISIBLE (-1950 3025);
FORCEPROP 1 LAST BODY_TYPE PLUMBING
J 0
(-1950 3075);
DISPLAY 0.872340 (-1950 3075);
PAINT GREEN (-1950 3075);
DISPLAY INVISIBLE (-1950 3075);
FORCEPROP 1 LAST HDL_TAP TRUE
J 0
(-1625 2900);
DISPLAY 0.872340 (-1625 2900);
DISPLAY INVISIBLE (-1625 2900);
FORCEPROP 1 LAST PATH I21
J 0
(-1952 3025);
DISPLAY 0.872340 (-1952 3025);
PAINT GREEN (-1952 3025);
DISPLAY INVISIBLE (-1952 3025);
FORCEADD TAP..1
(-1950 3375);
FORCEPROP 3 LASTPIN (-2000 3375) SIG_NAME P5E_CPU0_P3_RX_DN<1>
J 0
(-1990 3385);
DISPLAY 0.659574 (-1990 3385);
PAINT MONO (-1990 3385);
DISPLAY INVISIBLE (-1990 3385);
FORCEPROP 1 LASTPIN (-2000 3375) BN 1
J 0
(-2012 3383);
DISPLAY 0.680851 (-2012 3383);
PAINT GREEN (-2012 3383);
FORCEPROP 2 LAST CDS_LIB standard
J 0
(-1950 3375);
DISPLAY INVISIBLE (-1950 3375);
FORCEPROP 1 LAST BODY_TYPE PLUMBING
J 0
(-1950 3425);
DISPLAY 0.872340 (-1950 3425);
PAINT GREEN (-1950 3425);
DISPLAY INVISIBLE (-1950 3425);
FORCEPROP 1 LAST HDL_TAP TRUE
J 0
(-1625 3250);
DISPLAY 0.872340 (-1625 3250);
DISPLAY INVISIBLE (-1625 3250);
FORCEPROP 1 LAST PATH I22
J 0
(-1952 3375);
DISPLAY 0.872340 (-1952 3375);
PAINT GREEN (-1952 3375);
DISPLAY INVISIBLE (-1952 3375);
FORCEADD TAP..1
(-2150 3475);
FORCEPROP 3 LASTPIN (-2200 3475) SIG_NAME P5E_CPU0_P3_RX_DP<1>
J 0
(-2190 3485);
DISPLAY 0.659574 (-2190 3485);
PAINT MONO (-2190 3485);
DISPLAY INVISIBLE (-2190 3485);
FORCEPROP 1 LASTPIN (-2200 3475) BN 1
J 0
(-2212 3483);
DISPLAY 0.680851 (-2212 3483);
PAINT GREEN (-2212 3483);
FORCEPROP 2 LAST CDS_LIB standard
J 0
(-2150 3475);
DISPLAY INVISIBLE (-2150 3475);
FORCEPROP 1 LAST BODY_TYPE PLUMBING
J 0
(-2150 3525);
DISPLAY 0.872340 (-2150 3525);
PAINT GREEN (-2150 3525);
DISPLAY INVISIBLE (-2150 3525);
FORCEPROP 1 LAST HDL_TAP TRUE
J 0
(-1825 3350);
DISPLAY 0.872340 (-1825 3350);
DISPLAY INVISIBLE (-1825 3350);
FORCEPROP 1 LAST PATH I23
J 0
(-2152 3475);
DISPLAY 0.872340 (-2152 3475);
PAINT GREEN (-2152 3475);
DISPLAY INVISIBLE (-2152 3475);
FORCEADD TAP..1
(-2150 3825);
FORCEPROP 3 LASTPIN (-2200 3825) SIG_NAME P5E_CPU0_P3_RX_DP<2>
J 0
(-2190 3835);
DISPLAY 0.659574 (-2190 3835);
PAINT MONO (-2190 3835);
DISPLAY INVISIBLE (-2190 3835);
FORCEPROP 1 LASTPIN (-2200 3825) BN 2
J 0
(-2212 3833);
DISPLAY 0.680851 (-2212 3833);
PAINT GREEN (-2212 3833);
FORCEPROP 2 LAST CDS_LIB standard
J 0
(-2150 3825);
DISPLAY INVISIBLE (-2150 3825);
FORCEPROP 1 LAST BODY_TYPE PLUMBING
J 0
(-2150 3875);
DISPLAY 0.872340 (-2150 3875);
PAINT GREEN (-2150 3875);
DISPLAY INVISIBLE (-2150 3875);
FORCEPROP 1 LAST HDL_TAP TRUE
J 0
(-1825 3700);
DISPLAY 0.872340 (-1825 3700);
DISPLAY INVISIBLE (-1825 3700);
FORCEPROP 1 LAST PATH I24
J 0
(-2152 3825);
DISPLAY 0.872340 (-2152 3825);
PAINT GREEN (-2152 3825);
DISPLAY INVISIBLE (-2152 3825);
FORCEADD TAP..1
(-1950 3725);
FORCEPROP 3 LASTPIN (-2000 3725) SIG_NAME P5E_CPU0_P3_RX_DN<2>
J 0
(-1990 3735);
DISPLAY 0.659574 (-1990 3735);
PAINT MONO (-1990 3735);
DISPLAY INVISIBLE (-1990 3735);
FORCEPROP 1 LASTPIN (-2000 3725) BN 2
J 0
(-2012 3733);
DISPLAY 0.680851 (-2012 3733);
PAINT GREEN (-2012 3733);
FORCEPROP 2 LAST CDS_LIB standard
J 0
(-1950 3725);
DISPLAY INVISIBLE (-1950 3725);
FORCEPROP 1 LAST BODY_TYPE PLUMBING
J 0
(-1950 3775);
DISPLAY 0.872340 (-1950 3775);
PAINT GREEN (-1950 3775);
DISPLAY INVISIBLE (-1950 3775);
FORCEPROP 1 LAST HDL_TAP TRUE
J 0
(-1625 3600);
DISPLAY 0.872340 (-1625 3600);
DISPLAY INVISIBLE (-1625 3600);
FORCEPROP 1 LAST PATH I25
J 0
(-1952 3725);
DISPLAY 0.872340 (-1952 3725);
PAINT GREEN (-1952 3725);
DISPLAY INVISIBLE (-1952 3725);
FORCEADD TAP..1
(-2150 4175);
FORCEPROP 3 LASTPIN (-2200 4175) SIG_NAME P5E_CPU0_P3_RX_DP<3>
J 0
(-2190 4185);
DISPLAY 0.659574 (-2190 4185);
PAINT MONO (-2190 4185);
DISPLAY INVISIBLE (-2190 4185);
FORCEPROP 1 LASTPIN (-2200 4175) BN 3
J 0
(-2212 4183);
DISPLAY 0.680851 (-2212 4183);
PAINT GREEN (-2212 4183);
FORCEPROP 2 LAST CDS_LIB standard
J 0
(-2150 4175);
DISPLAY INVISIBLE (-2150 4175);
FORCEPROP 1 LAST BODY_TYPE PLUMBING
J 0
(-2150 4225);
DISPLAY 0.872340 (-2150 4225);
PAINT GREEN (-2150 4225);
DISPLAY INVISIBLE (-2150 4225);
FORCEPROP 1 LAST HDL_TAP TRUE
J 0
(-1825 4050);
DISPLAY 0.872340 (-1825 4050);
DISPLAY INVISIBLE (-1825 4050);
FORCEPROP 1 LAST PATH I26
J 0
(-2152 4175);
DISPLAY 0.872340 (-2152 4175);
PAINT GREEN (-2152 4175);
DISPLAY INVISIBLE (-2152 4175);
FORCEADD TAP..1
(-1950 4075);
FORCEPROP 3 LASTPIN (-2000 4075) SIG_NAME P5E_CPU0_P3_RX_DN<3>
J 0
(-1990 4085);
DISPLAY 0.659574 (-1990 4085);
PAINT MONO (-1990 4085);
DISPLAY INVISIBLE (-1990 4085);
FORCEPROP 1 LASTPIN (-2000 4075) BN 3
J 0
(-2012 4083);
DISPLAY 0.680851 (-2012 4083);
PAINT GREEN (-2012 4083);
FORCEPROP 2 LAST CDS_LIB standard
J 0
(-1950 4075);
DISPLAY INVISIBLE (-1950 4075);
FORCEPROP 1 LAST BODY_TYPE PLUMBING
J 0
(-1950 4125);
DISPLAY 0.872340 (-1950 4125);
PAINT GREEN (-1950 4125);
DISPLAY INVISIBLE (-1950 4125);
FORCEPROP 1 LAST HDL_TAP TRUE
J 0
(-1625 3950);
DISPLAY 0.872340 (-1625 3950);
DISPLAY INVISIBLE (-1625 3950);
FORCEPROP 1 LAST PATH I27
J 0
(-1952 4075);
DISPLAY 0.872340 (-1952 4075);
PAINT GREEN (-1952 4075);
DISPLAY INVISIBLE (-1952 4075);
FORCEADD TAP..1
(-1950 4425);
FORCEPROP 3 LASTPIN (-2000 4425) SIG_NAME P5E_CPU0_P3_RX_DN<4>
J 0
(-1990 4435);
DISPLAY 0.659574 (-1990 4435);
PAINT MONO (-1990 4435);
DISPLAY INVISIBLE (-1990 4435);
FORCEPROP 1 LASTPIN (-2000 4425) BN 4
J 0
(-2012 4433);
DISPLAY 0.680851 (-2012 4433);
PAINT GREEN (-2012 4433);
FORCEPROP 2 LAST CDS_LIB standard
J 0
(-1950 4425);
DISPLAY INVISIBLE (-1950 4425);
FORCEPROP 1 LAST BODY_TYPE PLUMBING
J 0
(-1950 4475);
DISPLAY 0.872340 (-1950 4475);
PAINT GREEN (-1950 4475);
DISPLAY INVISIBLE (-1950 4475);
FORCEPROP 1 LAST HDL_TAP TRUE
J 0
(-1625 4300);
DISPLAY 0.872340 (-1625 4300);
DISPLAY INVISIBLE (-1625 4300);
FORCEPROP 1 LAST PATH I28
J 0
(-1952 4425);
DISPLAY 0.872340 (-1952 4425);
PAINT GREEN (-1952 4425);
DISPLAY INVISIBLE (-1952 4425);
FORCEADD TAP..1
(-2150 4525);
FORCEPROP 3 LASTPIN (-2200 4525) SIG_NAME P5E_CPU0_P3_RX_DP<4>
J 0
(-2190 4535);
DISPLAY 0.659574 (-2190 4535);
PAINT MONO (-2190 4535);
DISPLAY INVISIBLE (-2190 4535);
FORCEPROP 1 LASTPIN (-2200 4525) BN 4
J 0
(-2212 4533);
DISPLAY 0.680851 (-2212 4533);
PAINT GREEN (-2212 4533);
FORCEPROP 2 LAST CDS_LIB standard
J 0
(-2150 4525);
DISPLAY INVISIBLE (-2150 4525);
FORCEPROP 1 LAST BODY_TYPE PLUMBING
J 0
(-2150 4575);
DISPLAY 0.872340 (-2150 4575);
PAINT GREEN (-2150 4575);
DISPLAY INVISIBLE (-2150 4575);
FORCEPROP 1 LAST HDL_TAP TRUE
J 0
(-1825 4400);
DISPLAY 0.872340 (-1825 4400);
DISPLAY INVISIBLE (-1825 4400);
FORCEPROP 1 LAST PATH I29
J 0
(-2152 4525);
DISPLAY 0.872340 (-2152 4525);
PAINT GREEN (-2152 4525);
DISPLAY INVISIBLE (-2152 4525);
FORCEADD TAP..1
(-6650 3525);
FORCEPROP 3 LASTPIN (-6700 3525) SIG_NAME P5E_CPU0_P3_RX_DP<9>
J 0
(-6690 3535);
DISPLAY 0.659574 (-6690 3535);
PAINT MONO (-6690 3535);
DISPLAY INVISIBLE (-6690 3535);
FORCEPROP 1 LASTPIN (-6700 3525) BN 9
J 0
(-6712 3533);
DISPLAY 0.680851 (-6712 3533);
PAINT GREEN (-6712 3533);
FORCEPROP 2 LAST CDS_LIB standard
J 0
(-6650 3525);
DISPLAY INVISIBLE (-6650 3525);
FORCEPROP 1 LAST BODY_TYPE PLUMBING
J 0
(-6650 3575);
DISPLAY 0.872340 (-6650 3575);
PAINT GREEN (-6650 3575);
DISPLAY INVISIBLE (-6650 3575);
FORCEPROP 1 LAST HDL_TAP TRUE
J 0
(-6325 3400);
DISPLAY 0.872340 (-6325 3400);
DISPLAY INVISIBLE (-6325 3400);
FORCEPROP 1 LAST PATH I3
J 0
(-6652 3525);
DISPLAY 0.872340 (-6652 3525);
PAINT GREEN (-6652 3525);
DISPLAY INVISIBLE (-6652 3525);
FORCEADD TAP..1
(-2150 4875);
FORCEPROP 3 LASTPIN (-2200 4875) SIG_NAME P5E_CPU0_P3_RX_DP<5>
J 0
(-2190 4885);
DISPLAY 0.659574 (-2190 4885);
PAINT MONO (-2190 4885);
DISPLAY INVISIBLE (-2190 4885);
FORCEPROP 1 LASTPIN (-2200 4875) BN 5
J 0
(-2212 4883);
DISPLAY 0.680851 (-2212 4883);
PAINT GREEN (-2212 4883);
FORCEPROP 2 LAST CDS_LIB standard
J 0
(-2150 4875);
DISPLAY INVISIBLE (-2150 4875);
FORCEPROP 1 LAST BODY_TYPE PLUMBING
J 0
(-2150 4925);
DISPLAY 0.872340 (-2150 4925);
PAINT GREEN (-2150 4925);
DISPLAY INVISIBLE (-2150 4925);
FORCEPROP 1 LAST HDL_TAP TRUE
J 0
(-1825 4750);
DISPLAY 0.872340 (-1825 4750);
DISPLAY INVISIBLE (-1825 4750);
FORCEPROP 1 LAST PATH I30
J 0
(-2152 4875);
DISPLAY 0.872340 (-2152 4875);
PAINT GREEN (-2152 4875);
DISPLAY INVISIBLE (-2152 4875);
FORCEADD TAP..1
(-1950 4775);
FORCEPROP 3 LASTPIN (-2000 4775) SIG_NAME P5E_CPU0_P3_RX_DN<5>
J 0
(-1990 4785);
DISPLAY 0.659574 (-1990 4785);
PAINT MONO (-1990 4785);
DISPLAY INVISIBLE (-1990 4785);
FORCEPROP 1 LASTPIN (-2000 4775) BN 5
J 0
(-2012 4783);
DISPLAY 0.680851 (-2012 4783);
PAINT GREEN (-2012 4783);
FORCEPROP 2 LAST CDS_LIB standard
J 0
(-1950 4775);
DISPLAY INVISIBLE (-1950 4775);
FORCEPROP 1 LAST BODY_TYPE PLUMBING
J 0
(-1950 4825);
DISPLAY 0.872340 (-1950 4825);
PAINT GREEN (-1950 4825);
DISPLAY INVISIBLE (-1950 4825);
FORCEPROP 1 LAST HDL_TAP TRUE
J 0
(-1625 4650);
DISPLAY 0.872340 (-1625 4650);
DISPLAY INVISIBLE (-1625 4650);
FORCEPROP 1 LAST PATH I31
J 0
(-1952 4775);
DISPLAY 0.872340 (-1952 4775);
PAINT GREEN (-1952 4775);
DISPLAY INVISIBLE (-1952 4775);
FORCEADD TAP..1
(-2150 5225);
FORCEPROP 3 LASTPIN (-2200 5225) SIG_NAME P5E_CPU0_P3_RX_DP<6>
J 0
(-2190 5235);
DISPLAY 0.659574 (-2190 5235);
PAINT MONO (-2190 5235);
DISPLAY INVISIBLE (-2190 5235);
FORCEPROP 1 LASTPIN (-2200 5225) BN 6
J 0
(-2212 5233);
DISPLAY 0.680851 (-2212 5233);
PAINT GREEN (-2212 5233);
FORCEPROP 2 LAST CDS_LIB standard
J 0
(-2150 5225);
DISPLAY INVISIBLE (-2150 5225);
FORCEPROP 1 LAST BODY_TYPE PLUMBING
J 0
(-2150 5275);
DISPLAY 0.872340 (-2150 5275);
PAINT GREEN (-2150 5275);
DISPLAY INVISIBLE (-2150 5275);
FORCEPROP 1 LAST HDL_TAP TRUE
J 0
(-1825 5100);
DISPLAY 0.872340 (-1825 5100);
DISPLAY INVISIBLE (-1825 5100);
FORCEPROP 1 LAST PATH I32
J 0
(-2152 5225);
DISPLAY 0.872340 (-2152 5225);
PAINT GREEN (-2152 5225);
DISPLAY INVISIBLE (-2152 5225);
FORCEADD TAP..1
(-1950 5125);
FORCEPROP 3 LASTPIN (-2000 5125) SIG_NAME P5E_CPU0_P3_RX_DN<6>
J 0
(-1990 5135);
DISPLAY 0.659574 (-1990 5135);
PAINT MONO (-1990 5135);
DISPLAY INVISIBLE (-1990 5135);
FORCEPROP 1 LASTPIN (-2000 5125) BN 6
J 0
(-2012 5133);
DISPLAY 0.680851 (-2012 5133);
PAINT GREEN (-2012 5133);
FORCEPROP 2 LAST CDS_LIB standard
J 0
(-1950 5125);
DISPLAY INVISIBLE (-1950 5125);
FORCEPROP 1 LAST BODY_TYPE PLUMBING
J 0
(-1950 5175);
DISPLAY 0.872340 (-1950 5175);
PAINT GREEN (-1950 5175);
DISPLAY INVISIBLE (-1950 5175);
FORCEPROP 1 LAST HDL_TAP TRUE
J 0
(-1625 5000);
DISPLAY 0.872340 (-1625 5000);
DISPLAY INVISIBLE (-1625 5000);
FORCEPROP 1 LAST PATH I33
J 0
(-1952 5125);
DISPLAY 0.872340 (-1952 5125);
PAINT GREEN (-1952 5125);
DISPLAY INVISIBLE (-1952 5125);
FORCEADD TAP..1
(-1950 5475);
FORCEPROP 3 LASTPIN (-2000 5475) SIG_NAME P5E_CPU0_P3_RX_DN<7>
J 0
(-1990 5485);
DISPLAY 0.659574 (-1990 5485);
PAINT MONO (-1990 5485);
DISPLAY INVISIBLE (-1990 5485);
FORCEPROP 1 LASTPIN (-2000 5475) BN 7
J 0
(-2012 5483);
DISPLAY 0.680851 (-2012 5483);
PAINT GREEN (-2012 5483);
FORCEPROP 2 LAST CDS_LIB standard
J 0
(-1950 5475);
DISPLAY INVISIBLE (-1950 5475);
FORCEPROP 1 LAST BODY_TYPE PLUMBING
J 0
(-1950 5525);
DISPLAY 0.872340 (-1950 5525);
PAINT GREEN (-1950 5525);
DISPLAY INVISIBLE (-1950 5525);
FORCEPROP 1 LAST HDL_TAP TRUE
J 0
(-1625 5350);
DISPLAY 0.872340 (-1625 5350);
DISPLAY INVISIBLE (-1625 5350);
FORCEPROP 1 LAST PATH I34
J 0
(-1952 5475);
DISPLAY 0.872340 (-1952 5475);
PAINT GREEN (-1952 5475);
DISPLAY INVISIBLE (-1952 5475);
FORCEADD TAP..1
(-2150 5575);
FORCEPROP 3 LASTPIN (-2200 5575) SIG_NAME P5E_CPU0_P3_RX_DP<7>
J 0
(-2190 5585);
DISPLAY 0.659574 (-2190 5585);
PAINT MONO (-2190 5585);
DISPLAY INVISIBLE (-2190 5585);
FORCEPROP 1 LASTPIN (-2200 5575) BN 7
J 0
(-2212 5583);
DISPLAY 0.680851 (-2212 5583);
PAINT GREEN (-2212 5583);
FORCEPROP 2 LAST CDS_LIB standard
J 0
(-2150 5575);
DISPLAY INVISIBLE (-2150 5575);
FORCEPROP 1 LAST BODY_TYPE PLUMBING
J 0
(-2150 5625);
DISPLAY 0.872340 (-2150 5625);
PAINT GREEN (-2150 5625);
DISPLAY INVISIBLE (-2150 5625);
FORCEPROP 1 LAST HDL_TAP TRUE
J 0
(-1825 5450);
DISPLAY 0.872340 (-1825 5450);
DISPLAY INVISIBLE (-1825 5450);
FORCEPROP 1 LAST PATH I35
J 0
(-2152 5575);
DISPLAY 0.872340 (-2152 5575);
PAINT GREEN (-2152 5575);
DISPLAY INVISIBLE (-2152 5575);
FORCEADD OFFPAGE..5
R 2
(-950 5500);
FORCEPROP 2 LAST $XR0 25 
J 0
(-761 5500);
DISPLAY 0.638298 (-761 5500);
PAINT MONO (-761 5500);
FORCEPROP 2 LAST CDS_LIB standard
J 0
(-950 5500);
DISPLAY INVISIBLE (-950 5500);
FORCEPROP 1 LAST OFFPAGE TRUE
J 2
(-1275 5375);
DISPLAY 0.872340 (-1275 5375);
PAINT GREEN (-1275 5375);
DISPLAY INVISIBLE (-1275 5375);
FORCEPROP 1 LAST COMMENT_BODY TRUE
J 2
(-1050 5425);
DISPLAY 0.872340 (-1050 5425);
PAINT GREEN (-1050 5425);
DISPLAY INVISIBLE (-1050 5425);
FORCEPROP 2 LAST PATH I36
J 0
(-775 5575);
DISPLAY 0.680851 (-775 5575);
DISPLAY INVISIBLE (-775 5575);
FORCEADD OFFPAGE..5
R 2
(-950 5600);
FORCEPROP 2 LAST $XR0 25 
J 0
(-761 5600);
DISPLAY 0.638298 (-761 5600);
PAINT MONO (-761 5600);
FORCEPROP 2 LAST CDS_LIB standard
J 0
(-950 5600);
DISPLAY INVISIBLE (-950 5600);
FORCEPROP 1 LAST OFFPAGE TRUE
J 2
(-1275 5475);
DISPLAY 0.872340 (-1275 5475);
PAINT GREEN (-1275 5475);
DISPLAY INVISIBLE (-1275 5475);
FORCEPROP 1 LAST COMMENT_BODY TRUE
J 2
(-1050 5525);
DISPLAY 0.872340 (-1050 5525);
PAINT GREEN (-1050 5525);
DISPLAY INVISIBLE (-1050 5525);
FORCEPROP 2 LAST PATH I37
J 0
(-775 5675);
DISPLAY 0.680851 (-775 5675);
DISPLAY INVISIBLE (-775 5675);
FORCEADD PT5161LRS..7
(-3175 4325);
FORCEPROP 1 LAST LOCATION U6013
J 0
(-3525 5950);
DISPLAY 0.723404 (-3525 5950);
PAINT GREEN (-3525 5950);
FORCEPROP 0 LAST $SEC 7
J 0
(-3525 6100);
DISPLAY 0.680851 (-3525 6100);
PAINT MONO (-3525 6100);
DISPLAY INVISIBLE (-3525 6100);
FORCEPROP 0 LAST CDS_SEC 7
J 0
(-3525 6100);
DISPLAY 0.680851 (-3525 6100);
DISPLAY INVISIBLE (-3525 6100);
FORCEPROP 0 LASTPIN (-2725 5475) $PN CK29
J 0
(-2715 5485);
DISPLAY 0.680851 (-2715 5485);
PAINT MONO (-2715 5485);
FORCEPROP 0 LASTPIN (-2725 5125) $PN CU29
J 0
(-2715 5135);
DISPLAY 0.680851 (-2715 5135);
PAINT MONO (-2715 5135);
FORCEPROP 0 LASTPIN (-2725 4775) $PN DD29
J 0
(-2715 4785);
DISPLAY 0.680851 (-2715 4785);
PAINT MONO (-2715 4785);
FORCEPROP 0 LASTPIN (-2725 4425) $PN DL29
J 0
(-2715 4435);
DISPLAY 0.680851 (-2715 4435);
PAINT MONO (-2715 4435);
FORCEPROP 0 LASTPIN (-2725 4075) $PN DV29
J 0
(-2715 4085);
DISPLAY 0.680851 (-2715 4085);
PAINT MONO (-2715 4085);
FORCEPROP 0 LASTPIN (-2725 3725) $PN EE29
J 0
(-2715 3735);
DISPLAY 0.680851 (-2715 3735);
PAINT MONO (-2715 3735);
FORCEPROP 0 LASTPIN (-2725 3375) $PN EM29
J 0
(-2715 3385);
DISPLAY 0.680851 (-2715 3385);
PAINT MONO (-2715 3385);
FORCEPROP 0 LASTPIN (-2725 3025) $PN EW29
J 0
(-2715 3035);
DISPLAY 0.680851 (-2715 3035);
PAINT MONO (-2715 3035);
FORCEPROP 0 LASTPIN (-2725 5575) $PN CH26
J 0
(-2715 5585);
DISPLAY 0.680851 (-2715 5585);
PAINT MONO (-2715 5585);
FORCEPROP 0 LASTPIN (-2725 5225) $PN CR26
J 0
(-2715 5235);
DISPLAY 0.680851 (-2715 5235);
PAINT MONO (-2715 5235);
FORCEPROP 0 LASTPIN (-2725 4875) $PN DB26
J 0
(-2715 4885);
DISPLAY 0.680851 (-2715 4885);
PAINT MONO (-2715 4885);
FORCEPROP 0 LASTPIN (-2725 4525) $PN DJ26
J 0
(-2715 4535);
DISPLAY 0.680851 (-2715 4535);
PAINT MONO (-2715 4535);
FORCEPROP 0 LASTPIN (-2725 4175) $PN DT26
J 0
(-2715 4185);
DISPLAY 0.680851 (-2715 4185);
PAINT MONO (-2715 4185);
FORCEPROP 0 LASTPIN (-2725 3825) $PN EC26
J 0
(-2715 3835);
DISPLAY 0.680851 (-2715 3835);
PAINT MONO (-2715 3835);
FORCEPROP 0 LASTPIN (-2725 3475) $PN EK26
J 0
(-2715 3485);
DISPLAY 0.680851 (-2715 3485);
PAINT MONO (-2715 3485);
FORCEPROP 0 LASTPIN (-2725 3125) $PN EU26
J 0
(-2715 3135);
DISPLAY 0.680851 (-2715 3135);
PAINT MONO (-2715 3135);
FORCEPROP 1 LAST MATERIAL IC
J 0
(-3525 5800);
DISPLAY 0.723404 (-3525 5800);
PAINT GREEN (-3525 5800);
FORCEPROP 2 LAST VALUE PT5161LRS
J 0
(-3525 6000);
DISPLAY 0.680851 (-3525 6000);
FORCEPROP 2 LAST PART_TYPE SMLF
J 0
(-3525 6050);
DISPLAY 0.680851 (-3525 6050);
FORCEPROP 2 LAST CDS_LIB pure_quanta
J 0
(-3175 4325);
DISPLAY INVISIBLE (-3175 4325);
FORCEPROP 1 LAST CDS_LMAN_SYM_OUTLINE -350,1450,300,-1400
J 0
(-3175 4325);
DISPLAY 0.468085 (-3175 4325);
PAINT GREEN (-3175 4325);
DISPLAY INVISIBLE (-3175 4325);
FORCEPROP 1 LAST NEEDS_NO_SIZE TRUE
J 0
(-3175 4325);
DISPLAY 0.723404 (-3175 4325);
PAINT GREEN (-3175 4325);
DISPLAY INVISIBLE (-3175 4325);
FORCEPROP 1 LAST PATH I38
J 0
(-3175 4325);
DISPLAY 0.723404 (-3175 4325);
PAINT GREEN (-3175 4325);
DISPLAY INVISIBLE (-3175 4325);
FORCEPROP 1 LAST PART_NUMBER AJ051610U03
J 0
(-3525 5875);
DISPLAY 0.723404 (-3525 5875);
PAINT GREEN (-3525 5875);
DISPLAY INVISIBLE (-3525 5875);
FORCEADD TAP..1
(-6450 3075);
FORCEPROP 3 LASTPIN (-6500 3075) SIG_NAME P5E_CPU0_P3_RX_DN<8>
J 0
(-6490 3085);
DISPLAY 0.659574 (-6490 3085);
PAINT MONO (-6490 3085);
DISPLAY INVISIBLE (-6490 3085);
FORCEPROP 1 LASTPIN (-6500 3075) BN 8
J 0
(-6512 3083);
DISPLAY 0.680851 (-6512 3083);
PAINT GREEN (-6512 3083);
FORCEPROP 2 LAST CDS_LIB standard
J 0
(-6450 3075);
DISPLAY INVISIBLE (-6450 3075);
FORCEPROP 1 LAST BODY_TYPE PLUMBING
J 0
(-6450 3125);
DISPLAY 0.872340 (-6450 3125);
PAINT GREEN (-6450 3125);
DISPLAY INVISIBLE (-6450 3125);
FORCEPROP 1 LAST HDL_TAP TRUE
J 0
(-6125 2950);
DISPLAY 0.872340 (-6125 2950);
DISPLAY INVISIBLE (-6125 2950);
FORCEPROP 1 LAST PATH I4
J 0
(-6452 3075);
DISPLAY 0.872340 (-6452 3075);
PAINT GREEN (-6452 3075);
DISPLAY INVISIBLE (-6452 3075);
FORCEADD TAP..1
(-6450 3425);
FORCEPROP 3 LASTPIN (-6500 3425) SIG_NAME P5E_CPU0_P3_RX_DN<9>
J 0
(-6490 3435);
DISPLAY 0.659574 (-6490 3435);
PAINT MONO (-6490 3435);
DISPLAY INVISIBLE (-6490 3435);
FORCEPROP 1 LASTPIN (-6500 3425) BN 9
J 0
(-6512 3433);
DISPLAY 0.680851 (-6512 3433);
PAINT GREEN (-6512 3433);
FORCEPROP 2 LAST CDS_LIB standard
J 0
(-6450 3425);
DISPLAY INVISIBLE (-6450 3425);
FORCEPROP 1 LAST BODY_TYPE PLUMBING
J 0
(-6450 3475);
DISPLAY 0.872340 (-6450 3475);
PAINT GREEN (-6450 3475);
DISPLAY INVISIBLE (-6450 3475);
FORCEPROP 1 LAST HDL_TAP TRUE
J 0
(-6125 3300);
DISPLAY 0.872340 (-6125 3300);
DISPLAY INVISIBLE (-6125 3300);
FORCEPROP 1 LAST PATH I5
J 0
(-6452 3425);
DISPLAY 0.872340 (-6452 3425);
PAINT GREEN (-6452 3425);
DISPLAY INVISIBLE (-6452 3425);
FORCEADD TAP..1
(-6650 3875);
FORCEPROP 3 LASTPIN (-6700 3875) SIG_NAME P5E_CPU0_P3_RX_DP<10>
J 0
(-6690 3885);
DISPLAY 0.659574 (-6690 3885);
PAINT MONO (-6690 3885);
DISPLAY INVISIBLE (-6690 3885);
FORCEPROP 1 LASTPIN (-6700 3875) BN 10
J 0
(-6712 3883);
DISPLAY 0.680851 (-6712 3883);
PAINT GREEN (-6712 3883);
FORCEPROP 2 LAST CDS_LIB standard
J 0
(-6650 3875);
DISPLAY INVISIBLE (-6650 3875);
FORCEPROP 1 LAST BODY_TYPE PLUMBING
J 0
(-6650 3925);
DISPLAY 0.872340 (-6650 3925);
PAINT GREEN (-6650 3925);
DISPLAY INVISIBLE (-6650 3925);
FORCEPROP 1 LAST HDL_TAP TRUE
J 0
(-6325 3750);
DISPLAY 0.872340 (-6325 3750);
DISPLAY INVISIBLE (-6325 3750);
FORCEPROP 1 LAST PATH I6
J 0
(-6652 3875);
DISPLAY 0.872340 (-6652 3875);
PAINT GREEN (-6652 3875);
DISPLAY INVISIBLE (-6652 3875);
FORCEADD TAP..1
(-6650 4225);
FORCEPROP 3 LASTPIN (-6700 4225) SIG_NAME P5E_CPU0_P3_RX_DP<11>
J 0
(-6690 4235);
DISPLAY 0.659574 (-6690 4235);
PAINT MONO (-6690 4235);
DISPLAY INVISIBLE (-6690 4235);
FORCEPROP 1 LASTPIN (-6700 4225) BN 11
J 0
(-6712 4233);
DISPLAY 0.680851 (-6712 4233);
PAINT GREEN (-6712 4233);
FORCEPROP 2 LAST CDS_LIB standard
J 0
(-6650 4225);
DISPLAY INVISIBLE (-6650 4225);
FORCEPROP 1 LAST BODY_TYPE PLUMBING
J 0
(-6650 4275);
DISPLAY 0.872340 (-6650 4275);
PAINT GREEN (-6650 4275);
DISPLAY INVISIBLE (-6650 4275);
FORCEPROP 1 LAST HDL_TAP TRUE
J 0
(-6325 4100);
DISPLAY 0.872340 (-6325 4100);
DISPLAY INVISIBLE (-6325 4100);
FORCEPROP 1 LAST PATH I7
J 0
(-6652 4225);
DISPLAY 0.872340 (-6652 4225);
PAINT GREEN (-6652 4225);
DISPLAY INVISIBLE (-6652 4225);
FORCEADD TAP..1
(-6650 4575);
FORCEPROP 3 LASTPIN (-6700 4575) SIG_NAME P5E_CPU0_P3_RX_DP<12>
J 0
(-6690 4585);
DISPLAY 0.659574 (-6690 4585);
PAINT MONO (-6690 4585);
DISPLAY INVISIBLE (-6690 4585);
FORCEPROP 1 LASTPIN (-6700 4575) BN 12
J 0
(-6712 4583);
DISPLAY 0.680851 (-6712 4583);
PAINT GREEN (-6712 4583);
FORCEPROP 2 LAST CDS_LIB standard
J 0
(-6650 4575);
DISPLAY INVISIBLE (-6650 4575);
FORCEPROP 1 LAST BODY_TYPE PLUMBING
J 0
(-6650 4625);
DISPLAY 0.872340 (-6650 4625);
PAINT GREEN (-6650 4625);
DISPLAY INVISIBLE (-6650 4625);
FORCEPROP 1 LAST HDL_TAP TRUE
J 0
(-6325 4450);
DISPLAY 0.872340 (-6325 4450);
DISPLAY INVISIBLE (-6325 4450);
FORCEPROP 1 LAST PATH I8
J 0
(-6652 4575);
DISPLAY 0.872340 (-6652 4575);
PAINT GREEN (-6652 4575);
DISPLAY INVISIBLE (-6652 4575);
FORCEADD TAP..1
(-6450 3775);
FORCEPROP 3 LASTPIN (-6500 3775) SIG_NAME P5E_CPU0_P3_RX_DN<10>
J 0
(-6490 3785);
DISPLAY 0.659574 (-6490 3785);
PAINT MONO (-6490 3785);
DISPLAY INVISIBLE (-6490 3785);
FORCEPROP 1 LASTPIN (-6500 3775) BN 10
J 0
(-6512 3783);
DISPLAY 0.680851 (-6512 3783);
PAINT GREEN (-6512 3783);
FORCEPROP 2 LAST CDS_LIB standard
J 0
(-6450 3775);
DISPLAY INVISIBLE (-6450 3775);
FORCEPROP 1 LAST BODY_TYPE PLUMBING
J 0
(-6450 3825);
DISPLAY 0.872340 (-6450 3825);
PAINT GREEN (-6450 3825);
DISPLAY INVISIBLE (-6450 3825);
FORCEPROP 1 LAST HDL_TAP TRUE
J 0
(-6125 3650);
DISPLAY 0.872340 (-6125 3650);
DISPLAY INVISIBLE (-6125 3650);
FORCEPROP 1 LAST PATH I9
J 0
(-6452 3775);
DISPLAY 0.872340 (-6452 3775);
PAINT GREEN (-6452 3775);
DISPLAY INVISIBLE (-6452 3775);
FORCEADD QUANTA_TITLE_BLOCK_C..1
(0 0);
FORCEPROP 0 LAST CDS_CON_LAST_MODIFIED Thu Sep 14 16:12:53 2023
J 0
(-1885 15);
DISPLAY INVISIBLE (-1885 15);
FORCEPROP 1 LAST CUSTOM_TXT_CDS <CON_LAST_MODIFIED>
J 0
(-1885 15);
DISPLAY 0.978723 (-1885 15);
FORCEPROP 2 LAST CUSTOM_TXT_CDS <XR_PAGE_TITLE>
J 0
(-7890 5250);
DISPLAY 0.638298 (-7890 5250);
PAINT PINK (-7890 5250);
DISPLAY INVISIBLE (-7890 5250);
FORCEPROP 1 LAST CUSTOM_TXT_CDS <NAME_2>
J 0
(-3175 50);
FORCEPROP 1 LAST CUSTOM_TXT_CDS <NAME_1>
J 0
(-3175 175);
FORCEPROP 1 LAST CUSTOM_TXT_CDS <Q_NUMBER>
J 0
(-1403 103);
DISPLAY 1.212766 (-1403 103);
FORCEPROP 1 LAST CUSTOM_TXT_CDS <Q_PROJ>
J 0
(-2382 102);
DISPLAY 1.212766 (-2382 102);
FORCEPROP 1 LAST CUSTOM_TXT_CDS <Q_REV>
J 0
(-184 103);
DISPLAY 1.212766 (-184 103);
FORCEPROP 1 LAST CUSTOM_TXT_CDS <CON_PAGE_NUM> OF <CON_TOTAL_PAGES>
J 0
(-446 18);
DISPLAY 0.978723 (-446 18);
FORCEPROP 1 LAST Q_TITLE RETIMER_CPU0_P3(2)
J 0
(-9366 26);
DISPLAY 2.446809 (-9366 26);
PAINT GREEN (-9366 26);
FORCEPROP 2 LAST PAGE_BORDER TRUE
J 0
(-7890 5250);
DISPLAY 0.638298 (-7890 5250);
PAINT PINK (-7890 5250);
DISPLAY INVISIBLE (-7890 5250);
FORCEPROP 1 LAST CDS_LMAN_SYM_OUTLINE -9475,6775,100,-125
J 0
(0 0);
DISPLAY 0.468085 (0 0);
PAINT GREEN (0 0);
DISPLAY INVISIBLE (0 0);
FORCEPROP 2 LAST CDS_LIB pure_quanta
J 0
(0 0);
DISPLAY INVISIBLE (0 0);
FORCEPROP 2 LAST CDS_XR_PAGE_TITLE CR-307 : @T6G_MB_LIB.T6G(SCH_1):PAGE307
J 0
(-7890 5250);
DISPLAY 0.638298 (-7890 5250);
PAINT PINK (-7890 5250);
DISPLAY INVISIBLE (-7890 5250);
FORCEPROP 1 LAST Q_DEPT BU9
J 1
(-3763 49);
DISPLAY 1.957447 (-3763 49);
PAINT GREEN (-3763 49);
DISPLAY INVISIBLE (-3763 49);
FORCEPROP 1 LAST COMMENT_BODY TRUE
J 0
(12 -13);
DISPLAY 0.978723 (12 -13);
PAINT GREEN (12 -13);
DISPLAY INVISIBLE (12 -13);
WIRE 17 -1 (-2100 4900)(-2100 4550);
WIRE 17 -1 (-2100 5250)(-2100 4900);
WIRE 17 -1 (-2100 4200)(-2100 4550);
WIRE 17 -1 (-2100 4200)(-2100 3850);
WIRE 17 -1 (-2100 5600)(-2100 5250);
WIRE 17 -1 (-2100 5600)(-1000 5600);
FORCEPROP 2 LAST SIG_NAME P5E_CPU0_P3_RX_DP<7:0>
J 0
(-1835 5610);
DISPLAY 0.680851 (-1835 5610);
PAINT WHITE (-1835 5610);
WIRE 17 -1 (-6600 5300)(-6600 4950);
WIRE 17 -1 (-6600 5650)(-6600 5300);
WIRE 17 -1 (-6600 4950)(-6600 4600);
WIRE 17 -1 (-6600 4250)(-6600 4600);
WIRE 17 -1 (-6600 5725)(-6600 5650);
WIRE 17 -1 (-6600 5725)(-5475 5725);
FORCEPROP 2 LAST SIG_NAME P5E_CPU0_P3_RX_DP<15:8>
J 0
(-6335 5735);
DISPLAY 0.680851 (-6335 5735);
PAINT WHITE (-6335 5735);
WIRE 17 -1 (-6600 4250)(-6600 3900);
WIRE 17 -1 (-6600 3900)(-6600 3550);
WIRE 17 -1 (-6600 3550)(-6600 3200);
WIRE 17 -1 (-2100 3850)(-2100 3500);
WIRE 17 -1 (-2100 3500)(-2100 3150);
WIRE 17 -1 (-6400 5200)(-6400 4850);
WIRE 17 -1 (-6400 5550)(-6400 5200);
WIRE 17 -1 (-6400 4850)(-6400 4500);
WIRE 17 -1 (-6400 4150)(-6400 4500);
WIRE 17 -1 (-6400 5600)(-6400 5550);
WIRE 17 -1 (-6400 5600)(-5500 5600);
FORCEPROP 2 LAST SIG_NAME P5E_CPU0_P3_RX_DN<15:8>
J 0
(-6335 5610);
DISPLAY 0.680851 (-6335 5610);
PAINT WHITE (-6335 5610);
WIRE 17 -1 (-1900 4800)(-1900 4450);
WIRE 17 -1 (-1900 5150)(-1900 4800);
WIRE 17 -1 (-1900 4100)(-1900 4450);
WIRE 17 -1 (-1900 4100)(-1900 3750);
WIRE 17 -1 (-1900 5500)(-1900 5150);
WIRE 17 -1 (-1900 5500)(-1000 5500);
FORCEPROP 2 LAST SIG_NAME P5E_CPU0_P3_RX_DN<7:0>
J 0
(-1835 5510);
DISPLAY 0.680851 (-1835 5510);
PAINT WHITE (-1835 5510);
WIRE 17 -1 (-1900 3750)(-1900 3400);
WIRE 17 -1 (-1900 3400)(-1900 3050);
WIRE 17 -1 (-6400 4150)(-6400 3800);
WIRE 17 -1 (-6400 3800)(-6400 3450);
WIRE 17 -1 (-6400 3450)(-6400 3100);
WIRE 16 -1 (-7225 5525)(-6500 5525);
WIRE 16 -1 (-7225 5275)(-6700 5275);
WIRE 16 -1 (-7225 5175)(-6500 5175);
WIRE 16 -1 (-7225 4475)(-6500 4475);
WIRE 16 -1 (-7225 3075)(-6500 3075);
WIRE 16 -1 (-7225 3425)(-6500 3425);
WIRE 16 -1 (-7225 3775)(-6500 3775);
WIRE 16 -1 (-2725 3025)(-2000 3025);
WIRE 16 -1 (-2725 3375)(-2000 3375);
WIRE 16 -1 (-2725 5125)(-2000 5125);
WIRE 16 -1 (-2725 5475)(-2000 5475);
WIRE 16 -1 (-2725 3725)(-2000 3725);
WIRE 16 -1 (-7225 4125)(-6500 4125);
WIRE 16 -1 (-2725 4775)(-2000 4775);
WIRE 16 -1 (-2725 4075)(-2000 4075);
WIRE 16 -1 (-2725 4425)(-2000 4425);
WIRE 16 -1 (-7225 4825)(-6500 4825);
WIRE 16 -1 (-7225 5625)(-6700 5625);
WIRE 16 -1 (-2725 5225)(-2200 5225);
WIRE 16 -1 (-2725 3125)(-2200 3125);
WIRE 16 -1 (-2725 3475)(-2200 3475);
WIRE 16 -1 (-2725 3825)(-2200 3825);
WIRE 16 -1 (-2725 4175)(-2200 4175);
WIRE 16 -1 (-2725 5575)(-2200 5575);
WIRE 16 -1 (-7225 4575)(-6700 4575);
WIRE 16 -1 (-7225 3175)(-6700 3175);
WIRE 16 -1 (-7225 3525)(-6700 3525);
WIRE 16 -1 (-7225 3875)(-6700 3875);
WIRE 16 -1 (-7225 4225)(-6700 4225);
WIRE 16 -1 (-2725 4875)(-2200 4875);
WIRE 16 -1 (-7225 4925)(-6700 4925);
WIRE 16 -1 (-2725 4525)(-2200 4525);
FORCENOTE
RETIMER TO CPU
(-8025 2600) 0;
DISPLAY LEFT (-8025 2600);
DISPLAY 3.148936 (-8025 2600);
FORCENOTE
RETIMER TO CPU
(-3550 2550) 0;
DISPLAY LEFT (-3550 2550);
DISPLAY 3.148936 (-3550 2550);
FORCENOTE
P5E_CPU0_P3_RX_DP/DN<0-15> LANE REVERSAL
(-9025 6300) 0;
DISPLAY LEFT (-9025 6300);
DISPLAY 2.000000 (-9025 6300);
QUIT
